FILE_TYPE = CONNECTIVITY;
{Allegro Design Entry HDL 17.2-2016 S081 (4005846) 1/11/2022}
"PAGE_NUMBER" = 202;
0"NC";
END.
